(kicad_pcb
	(version 20260206)
	(generator "pcbnew")
	(generator_version "10.0")
	(general
		(thickness 1.6)
		(legacy_teardrops no)
	)
	(paper "A4")
	(title_block
		(title "Wiwynn_Tioga_Pass_MB.brd")
		(comment 1 "Tioga Pass / footprints 1907-1914 of 4770")
	)
	(layers
		(0 "F.Cu" signal "TOP")
		(4 "In1.Cu" signal "L2GND")
		(6 "In2.Cu" signal "L3")
		(8 "In3.Cu" signal "L4GND")
		(10 "In4.Cu" signal "L5")
		(12 "In5.Cu" signal "L6GND")
		(14 "In6.Cu" signal "L7VCC")
		(16 "In7.Cu" signal "L8VCC")
		(18 "In8.Cu" signal "L9GND")
		(20 "In9.Cu" signal "L10")
		(22 "In10.Cu" signal "L11GND")
		(24 "In11.Cu" signal "L12")
		(26 "In12.Cu" signal "L13GND")
		(2 "B.Cu" signal "BOTTOM")
		(9 "F.Adhes" user "F.Adhesive")
		(11 "B.Adhes" user "B.Adhesive")
		(13 "F.Paste" user "Package Geometry/Pastemask Top")
		(15 "B.Paste" user "Package Geometry/Pastemask Bottom")
		(5 "F.SilkS" user "Ref Des/Silkscreen Top")
		(7 "B.SilkS" user "Ref Des/Silkscreen Bottom")
		(1 "F.Mask" user "Board Geometry/Soldermask Top")
		(3 "B.Mask" user "Board Geometry/Soldermask Bottom")
		(17 "Dwgs.User" user "User.Drawings")
		(19 "Cmts.User" user "User.Comments")
		(21 "Eco1.User" user "User.Eco1")
		(23 "Eco2.User" user "User.Eco2")
		(25 "Edge.Cuts" user "Board Geometry/Outline")
		(27 "Margin" user)
		(31 "F.CrtYd" user "Package Geometry/Place Bound Top")
		(29 "B.CrtYd" user "Package Geometry/Place Bound Bottom")
		(35 "F.Fab" user "Ref Des/Assembly Top")
		(33 "B.Fab" user "Ref Des/Assembly Bottom")
	)
	(footprint ""
		(layer "F.Cu")
		(at 401.319492 -10.917936)
		(property "Reference" "C8G2"
			(at 0 0 0)
			(layer "F.SilkS")
			(hide yes)
			(effects
				(font
					(size 1.27 1.27)
				)
			)
		)
		(property "Value" ""
			(at 0 0 0)
			(layer "F.Fab")
			(effects
				(font
					(size 1.27 1.27)
				)
			)
		)
		(duplicate_pad_numbers_are_jumpers no)
		(fp_rect
			(start -0.3048 0.9906)
			(end 0.3048 -0.1016)
			(stroke
				(width 0)
				(type default)
			)
			(fill no)
			(layer "F.CrtYd")
		)
		(fp_line
			(start -0.3048 -0.1016)
			(end -0.3048 0.9906)
			(stroke
				(width 0.1)
				(type default)
			)
			(layer "F.Fab")
		)
		(fp_line
			(start -0.3048 0.9906)
			(end 0.3048 0.9906)
			(stroke
				(width 0.1)
				(type default)
			)
			(layer "F.Fab")
		)
		(fp_line
			(start 0.3048 -0.1016)
			(end -0.3048 -0.1016)
			(stroke
				(width 0.1)
				(type default)
			)
			(layer "F.Fab")
		)
		(fp_line
			(start 0.3048 0.9906)
			(end 0.3048 -0.1016)
			(stroke
				(width 0.1)
				(type default)
			)
			(layer "F.Fab")
		)
		(pad "1" smd rect
			(at 0 0)
			(size 0.508 0.508)
			(layers "F.Cu" "F.Mask" "F.Paste")
			(net "P3E_CPU0_PE2_SS_TXN<4>")
		)
		(pad "2" smd rect
			(at 0 0.889)
			(size 0.508 0.508)
			(layers "F.Cu" "F.Mask" "F.Paste")
			(net "P3E_CPU0_PE2_SS_C_TXN<4>")
		)
		(zone
			(layer "F.Cu")
			(hatch none 0.5)
			(connect_pads
				(clearance 0)
			)
			(min_thickness 0.25)
			(keepout
				(tracks not_allowed)
				(vias allowed)
				(pads allowed)
				(copperpour not_allowed)
				(footprints allowed)
			)
			(placement
				(enabled no)
				(sheetname "")
			)
			(fill
				(thermal_gap 0.5)
				(thermal_bridge_width 0.5)
				(island_removal_mode 0)
			)
			(polygon
				(pts
					(xy 401.065492 -10.282936) (xy 401.573492 -10.282936) (xy 401.573492 -10.663936) (xy 401.065492 -10.663936)
				)
			)
		)
		(zone
			(layer "F.Cu")
			(hatch none 0.5)
			(connect_pads
				(clearance 0)
			)
			(min_thickness 0.25)
			(keepout
				(tracks allowed)
				(vias not_allowed)
				(pads allowed)
				(copperpour not_allowed)
				(footprints allowed)
			)
			(placement
				(enabled no)
				(sheetname "")
			)
			(fill
				(thermal_gap 0.5)
				(thermal_bridge_width 0.5)
				(island_removal_mode 0)
			)
			(polygon
				(pts
					(xy 401.065492 -10.282936) (xy 401.573492 -10.282936) (xy 401.573492 -10.663936) (xy 401.065492 -10.663936)
				)
			)
		)
	)
	(footprint ""
		(layer "F.Cu")
		(at 360.765598 -10.916158)
		(property "Reference" "R8W13"
			(at -0.8382 -0.67818 0)
			(unlocked yes)
			(layer "F.SilkS")
			(effects
				(font
					(size 0.4064 0.254)
					(thickness 0.1524)
				)
				(justify left)
			)
		)
		(property "Value" ""
			(at 0 0 0)
			(layer "F.Fab")
			(effects
				(font
					(size 1.27 1.27)
				)
			)
		)
		(duplicate_pad_numbers_are_jumpers no)
		(fp_poly
			(pts
				(xy -0.2794 -0.1016) (xy 0.2794 -0.1016) (xy 0.2794 0.9906) (xy -0.2794 0.9906)
			)
			(stroke
				(width 0)
				(type default)
			)
			(fill no)
			(layer "F.CrtYd")
		)
		(fp_line
			(start -0.2794 -0.1016)
			(end -0.2794 0.9906)
			(stroke
				(width 0.1)
				(type default)
			)
			(layer "F.Fab")
		)
		(fp_line
			(start -0.2794 0.9906)
			(end 0.2794 0.9906)
			(stroke
				(width 0.1)
				(type default)
			)
			(layer "F.Fab")
		)
		(fp_line
			(start 0.2794 -0.1016)
			(end -0.2794 -0.1016)
			(stroke
				(width 0.1)
				(type default)
			)
			(layer "F.Fab")
		)
		(fp_line
			(start 0.2794 0.9906)
			(end 0.2794 -0.1016)
			(stroke
				(width 0.1)
				(type default)
			)
			(layer "F.Fab")
		)
		(pad "1" smd rect
			(at 0 0)
			(size 0.508 0.508)
			(layers "F.Cu" "F.Mask" "F.Paste")
			(net "JTAG_RISER_TDI_R")
		)
		(pad "2" smd rect
			(at 0 0.889)
			(size 0.508 0.508)
			(layers "F.Cu" "F.Mask" "F.Paste")
			(net "JTAG_RISER_TDI")
		)
		(zone
			(layer "F.Cu")
			(hatch none 0.5)
			(connect_pads
				(clearance 0)
			)
			(min_thickness 0.25)
			(keepout
				(tracks allowed)
				(vias not_allowed)
				(pads allowed)
				(copperpour not_allowed)
				(footprints allowed)
			)
			(placement
				(enabled no)
				(sheetname "")
			)
			(fill
				(thermal_gap 0.5)
				(thermal_bridge_width 0.5)
				(island_removal_mode 0)
			)
			(polygon
				(pts
					(xy 360.511598 -10.662158) (xy 361.019598 -10.662158) (xy 361.019598 -10.281158) (xy 360.511598 -10.281158)
				)
			)
		)
		(zone
			(layer "F.Cu")
			(hatch none 0.5)
			(connect_pads
				(clearance 0)
			)
			(min_thickness 0.25)
			(keepout
				(tracks not_allowed)
				(vias allowed)
				(pads allowed)
				(copperpour not_allowed)
				(footprints allowed)
			)
			(placement
				(enabled no)
				(sheetname "")
			)
			(fill
				(thermal_gap 0.5)
				(thermal_bridge_width 0.5)
				(island_removal_mode 0)
			)
			(polygon
				(pts
					(xy 360.511598 -10.281158) (xy 361.019598 -10.281158) (xy 361.019598 -10.662158) (xy 360.511598 -10.662158)
				)
			)
		)
	)
	(footprint ""
		(layer "F.Cu")
		(at 276.000464 -140.208 90)
		(property "Reference" "C5A19"
			(at 1.848866 0.752348 90)
			(unlocked yes)
			(layer "F.SilkS")
			(effects
				(font
					(size 1.27 0.9652)
					(thickness 0.1524)
				)
			)
		)
		(property "Value" ""
			(at 0 0 90)
			(layer "F.Fab")
			(effects
				(font
					(size 1.27 1.27)
				)
			)
		)
		(duplicate_pad_numbers_are_jumpers no)
		(fp_rect
			(start -0.500126 1.598422)
			(end 0.500126 -0.201422)
			(stroke
				(width 0)
				(type default)
			)
			(fill no)
			(layer "F.CrtYd")
		)
		(fp_line
			(start 0.500126 -0.201422)
			(end 0.500126 1.598422)
			(stroke
				(width 0.1)
				(type default)
			)
			(layer "F.Fab")
		)
		(fp_line
			(start -0.500126 -0.201422)
			(end 0.500126 -0.201422)
			(stroke
				(width 0.1)
				(type default)
			)
			(layer "F.Fab")
		)
		(fp_line
			(start 0.500126 1.598422)
			(end -0.500126 1.598422)
			(stroke
				(width 0.1)
				(type default)
			)
			(layer "F.Fab")
		)
		(fp_line
			(start -0.500126 1.598422)
			(end -0.500126 -0.201422)
			(stroke
				(width 0.1)
				(type default)
			)
			(layer "F.Fab")
		)
		(pad "1" smd rect
			(at 0 0)
			(size 0.889 0.9906)
			(layers "F.Cu" "F.Mask" "F.Paste")
			(net "PVDDQ_DEF")
		)
		(pad "2" smd rect
			(at 0 1.397)
			(size 0.889 0.9906)
			(layers "F.Cu" "F.Mask" "F.Paste")
			(net "GND")
		)
		(zone
			(layer "F.Cu")
			(hatch none 0.5)
			(connect_pads
				(clearance 0)
			)
			(min_thickness 0.25)
			(keepout
				(tracks allowed)
				(vias not_allowed)
				(pads allowed)
				(copperpour not_allowed)
				(footprints allowed)
			)
			(placement
				(enabled no)
				(sheetname "")
			)
			(fill
				(thermal_gap 0.5)
				(thermal_bridge_width 0.5)
				(island_removal_mode 0)
			)
			(polygon
				(pts
					(xy 276.952964 -139.7127) (xy 276.952964 -140.7033) (xy 276.444964 -140.7033) (xy 276.444964 -139.7127)
				)
			)
		)
		(zone
			(layer "F.Cu")
			(hatch none 0.5)
			(connect_pads
				(clearance 0)
			)
			(min_thickness 0.25)
			(keepout
				(tracks not_allowed)
				(vias allowed)
				(pads allowed)
				(copperpour not_allowed)
				(footprints allowed)
			)
			(placement
				(enabled no)
				(sheetname "")
			)
			(fill
				(thermal_gap 0.5)
				(thermal_bridge_width 0.5)
				(island_removal_mode 0)
			)
			(polygon
				(pts
					(xy 276.952964 -139.7127) (xy 276.952964 -140.7033) (xy 276.444964 -140.7033) (xy 276.444964 -139.7127)
				)
			)
		)
	)
	(footprint ""
		(layer "F.Cu")
		(at 265.675872 -77.636116)
		(property "Reference" "C5D30"
			(at 0 0 0)
			(layer "F.SilkS")
			(hide yes)
			(effects
				(font
					(size 1.27 1.27)
				)
			)
		)
		(property "Value" ""
			(at 0 0 0)
			(layer "F.Fab")
			(effects
				(font
					(size 1.27 1.27)
				)
			)
		)
		(duplicate_pad_numbers_are_jumpers no)
		(fp_poly
			(pts
				(xy -0.4953 -0.2032) (xy 0.4953 -0.2032) (xy 0.4953 1.6002) (xy -0.4953 1.6002)
			)
			(stroke
				(width 0)
				(type default)
			)
			(fill no)
			(layer "F.CrtYd")
		)
		(fp_line
			(start -0.4953 -0.2032)
			(end 0.4953 -0.2032)
			(stroke
				(width 0.1)
				(type default)
			)
			(layer "F.Fab")
		)
		(fp_line
			(start -0.4953 1.6002)
			(end -0.4953 -0.2032)
			(stroke
				(width 0.1)
				(type default)
			)
			(layer "F.Fab")
		)
		(fp_line
			(start 0.4953 -0.2032)
			(end 0.4953 1.6002)
			(stroke
				(width 0.1)
				(type default)
			)
			(layer "F.Fab")
		)
		(fp_line
			(start 0.4953 1.6002)
			(end -0.4953 1.6002)
			(stroke
				(width 0.1)
				(type default)
			)
			(layer "F.Fab")
		)
		(pad "1" smd rect
			(at 0 0)
			(size 0.762 0.889)
			(layers "F.Cu" "F.Mask" "F.Paste")
			(net "PVCCIN_CPU0")
		)
		(pad "2" smd rect
			(at 0 1.397)
			(size 0.762 0.889)
			(layers "F.Cu" "F.Mask" "F.Paste")
			(net "GND")
		)
		(zone
			(layer "F.Cu")
			(hatch none 0.5)
			(connect_pads
				(clearance 0)
			)
			(min_thickness 0.25)
			(keepout
				(tracks not_allowed)
				(vias allowed)
				(pads allowed)
				(copperpour not_allowed)
				(footprints allowed)
			)
			(placement
				(enabled no)
				(sheetname "")
			)
			(fill
				(thermal_gap 0.5)
				(thermal_bridge_width 0.5)
				(island_removal_mode 0)
			)
			(polygon
				(pts
					(xy 265.294872 -77.191616) (xy 266.056872 -77.191616) (xy 266.056872 -76.683616) (xy 265.294872 -76.683616)
				)
			)
		)
	)
	(footprint ""
		(layer "F.Cu")
		(at 272.861532 -140.208 90)
		(property "Reference" "C5A18"
			(at 1.848866 0.752348 90)
			(unlocked yes)
			(layer "F.SilkS")
			(effects
				(font
					(size 1.27 0.9652)
					(thickness 0.1524)
				)
			)
		)
		(property "Value" ""
			(at 0 0 90)
			(layer "F.Fab")
			(effects
				(font
					(size 1.27 1.27)
				)
			)
		)
		(duplicate_pad_numbers_are_jumpers no)
		(fp_rect
			(start -0.500126 1.598422)
			(end 0.500126 -0.201422)
			(stroke
				(width 0)
				(type default)
			)
			(fill no)
			(layer "F.CrtYd")
		)
		(fp_line
			(start 0.500126 -0.201422)
			(end 0.500126 1.598422)
			(stroke
				(width 0.1)
				(type default)
			)
			(layer "F.Fab")
		)
		(fp_line
			(start -0.500126 -0.201422)
			(end 0.500126 -0.201422)
			(stroke
				(width 0.1)
				(type default)
			)
			(layer "F.Fab")
		)
		(fp_line
			(start 0.500126 1.598422)
			(end -0.500126 1.598422)
			(stroke
				(width 0.1)
				(type default)
			)
			(layer "F.Fab")
		)
		(fp_line
			(start -0.500126 1.598422)
			(end -0.500126 -0.201422)
			(stroke
				(width 0.1)
				(type default)
			)
			(layer "F.Fab")
		)
		(pad "1" smd rect
			(at 0 0)
			(size 0.889 0.9906)
			(layers "F.Cu" "F.Mask" "F.Paste")
			(net "PVDDQ_DEF")
		)
		(pad "2" smd rect
			(at 0 1.397)
			(size 0.889 0.9906)
			(layers "F.Cu" "F.Mask" "F.Paste")
			(net "GND")
		)
		(zone
			(layer "F.Cu")
			(hatch none 0.5)
			(connect_pads
				(clearance 0)
			)
			(min_thickness 0.25)
			(keepout
				(tracks allowed)
				(vias not_allowed)
				(pads allowed)
				(copperpour not_allowed)
				(footprints allowed)
			)
			(placement
				(enabled no)
				(sheetname "")
			)
			(fill
				(thermal_gap 0.5)
				(thermal_bridge_width 0.5)
				(island_removal_mode 0)
			)
			(polygon
				(pts
					(xy 273.814032 -139.7127) (xy 273.814032 -140.7033) (xy 273.306032 -140.7033) (xy 273.306032 -139.7127)
				)
			)
		)
		(zone
			(layer "F.Cu")
			(hatch none 0.5)
			(connect_pads
				(clearance 0)
			)
			(min_thickness 0.25)
			(keepout
				(tracks not_allowed)
				(vias allowed)
				(pads allowed)
				(copperpour not_allowed)
				(footprints allowed)
			)
			(placement
				(enabled no)
				(sheetname "")
			)
			(fill
				(thermal_gap 0.5)
				(thermal_bridge_width 0.5)
				(island_removal_mode 0)
			)
			(polygon
				(pts
					(xy 273.814032 -139.7127) (xy 273.814032 -140.7033) (xy 273.306032 -140.7033) (xy 273.306032 -139.7127)
				)
			)
		)
	)
	(footprint ""
		(layer "F.Cu")
		(at 414.059116 -53.707792 180)
		(property "Reference" "R8E20"
			(at 0 0 180)
			(layer "F.SilkS")
			(hide yes)
			(effects
				(font
					(size 1.27 1.27)
				)
			)
		)
		(property "Value" ""
			(at 0 0 180)
			(layer "F.Fab")
			(effects
				(font
					(size 1.27 1.27)
				)
			)
		)
		(duplicate_pad_numbers_are_jumpers no)
		(fp_poly
			(pts
				(xy -0.2794 -0.1016) (xy 0.2794 -0.1016) (xy 0.2794 0.9906) (xy -0.2794 0.9906)
			)
			(stroke
				(width 0)
				(type default)
			)
			(fill no)
			(layer "F.CrtYd")
		)
		(fp_line
			(start 0.2794 0.9906)
			(end 0.2794 -0.1016)
			(stroke
				(width 0.1)
				(type default)
			)
			(layer "F.Fab")
		)
		(fp_line
			(start 0.2794 -0.1016)
			(end -0.2794 -0.1016)
			(stroke
				(width 0.1)
				(type default)
			)
			(layer "F.Fab")
		)
		(fp_line
			(start -0.2794 0.9906)
			(end 0.2794 0.9906)
			(stroke
				(width 0.1)
				(type default)
			)
			(layer "F.Fab")
		)
		(fp_line
			(start -0.2794 -0.1016)
			(end -0.2794 0.9906)
			(stroke
				(width 0.1)
				(type default)
			)
			(layer "F.Fab")
		)
		(pad "1" smd rect
			(at 0 0 180)
			(size 0.508 0.508)
			(layers "F.Cu" "F.Mask" "F.Paste")
			(net "FM_BIOS_TOP_SWAP_SPKR_R")
		)
		(pad "2" smd rect
			(at 0 0.889 180)
			(size 0.508 0.508)
			(layers "F.Cu" "F.Mask" "F.Paste")
			(net "FM_BIOS_TOP_SWAP_SPKR")
		)
		(zone
			(layer "F.Cu")
			(hatch none 0.5)
			(connect_pads
				(clearance 0)
			)
			(min_thickness 0.25)
			(keepout
				(tracks not_allowed)
				(vias allowed)
				(pads allowed)
				(copperpour not_allowed)
				(footprints allowed)
			)
			(placement
				(enabled no)
				(sheetname "")
			)
			(fill
				(thermal_gap 0.5)
				(thermal_bridge_width 0.5)
				(island_removal_mode 0)
			)
			(polygon
				(pts
					(xy 414.313116 -54.342792) (xy 413.805116 -54.342792) (xy 413.805116 -53.961792) (xy 414.313116 -53.961792)
				)
			)
		)
		(zone
			(layer "F.Cu")
			(hatch none 0.5)
			(connect_pads
				(clearance 0)
			)
			(min_thickness 0.25)
			(keepout
				(tracks allowed)
				(vias not_allowed)
				(pads allowed)
				(copperpour not_allowed)
				(footprints allowed)
			)
			(placement
				(enabled no)
				(sheetname "")
			)
			(fill
				(thermal_gap 0.5)
				(thermal_bridge_width 0.5)
				(island_removal_mode 0)
			)
			(polygon
				(pts
					(xy 414.313116 -53.961792) (xy 413.805116 -53.961792) (xy 413.805116 -54.342792) (xy 414.313116 -54.342792)
				)
			)
		)
	)
	(footprint ""
		(layer "F.Cu")
		(at 263.525 -84.709)
		(property "Reference" "C5D9"
			(at 0 0 0)
			(layer "F.SilkS")
			(hide yes)
			(effects
				(font
					(size 1.27 1.27)
				)
			)
		)
		(property "Value" ""
			(at 0 0 0)
			(layer "F.Fab")
			(effects
				(font
					(size 1.27 1.27)
				)
			)
		)
		(duplicate_pad_numbers_are_jumpers no)
		(fp_poly
			(pts
				(xy -0.4953 -0.2032) (xy 0.4953 -0.2032) (xy 0.4953 1.6002) (xy -0.4953 1.6002)
			)
			(stroke
				(width 0)
				(type default)
			)
			(fill no)
			(layer "F.CrtYd")
		)
		(fp_line
			(start -0.4953 -0.2032)
			(end 0.4953 -0.2032)
			(stroke
				(width 0.1)
				(type default)
			)
			(layer "F.Fab")
		)
		(fp_line
			(start -0.4953 1.6002)
			(end -0.4953 -0.2032)
			(stroke
				(width 0.1)
				(type default)
			)
			(layer "F.Fab")
		)
		(fp_line
			(start 0.4953 -0.2032)
			(end 0.4953 1.6002)
			(stroke
				(width 0.1)
				(type default)
			)
			(layer "F.Fab")
		)
		(fp_line
			(start 0.4953 1.6002)
			(end -0.4953 1.6002)
			(stroke
				(width 0.1)
				(type default)
			)
			(layer "F.Fab")
		)
		(pad "1" smd rect
			(at 0 0)
			(size 0.762 0.889)
			(layers "F.Cu" "F.Mask" "F.Paste")
			(net "PVDDQ_DEF")
		)
		(pad "2" smd rect
			(at 0 1.397)
			(size 0.762 0.889)
			(layers "F.Cu" "F.Mask" "F.Paste")
			(net "GND")
		)
		(zone
			(layer "F.Cu")
			(hatch none 0.5)
			(connect_pads
				(clearance 0)
			)
			(min_thickness 0.25)
			(keepout
				(tracks not_allowed)
				(vias allowed)
				(pads allowed)
				(copperpour not_allowed)
				(footprints allowed)
			)
			(placement
				(enabled no)
				(sheetname "")
			)
			(fill
				(thermal_gap 0.5)
				(thermal_bridge_width 0.5)
				(island_removal_mode 0)
			)
			(polygon
				(pts
					(xy 263.144 -84.2645) (xy 263.906 -84.2645) (xy 263.906 -83.7565) (xy 263.144 -83.7565)
				)
			)
		)
	)
	(footprint ""
		(layer "F.Cu")
		(at 260.697472 -73.318116)
		(property "Reference" "C5D41"
			(at 0 0 0)
			(layer "F.SilkS")
			(hide yes)
			(effects
				(font
					(size 1.27 1.27)
				)
			)
		)
		(property "Value" ""
			(at 0 0 0)
			(layer "F.Fab")
			(effects
				(font
					(size 1.27 1.27)
				)
			)
		)
		(duplicate_pad_numbers_are_jumpers no)
		(fp_poly
			(pts
				(xy -0.4953 -0.2032) (xy 0.4953 -0.2032) (xy 0.4953 1.6002) (xy -0.4953 1.6002)
			)
			(stroke
				(width 0)
				(type default)
			)
			(fill no)
			(layer "F.CrtYd")
		)
		(fp_line
			(start -0.4953 -0.2032)
			(end 0.4953 -0.2032)
			(stroke
				(width 0.1)
				(type default)
			)
			(layer "F.Fab")
		)
		(fp_line
			(start -0.4953 1.6002)
			(end -0.4953 -0.2032)
			(stroke
				(width 0.1)
				(type default)
			)
			(layer "F.Fab")
		)
		(fp_line
			(start 0.4953 -0.2032)
			(end 0.4953 1.6002)
			(stroke
				(width 0.1)
				(type default)
			)
			(layer "F.Fab")
		)
		(fp_line
			(start 0.4953 1.6002)
			(end -0.4953 1.6002)
			(stroke
				(width 0.1)
				(type default)
			)
			(layer "F.Fab")
		)
		(pad "1" smd rect
			(at 0 0)
			(size 0.762 0.889)
			(layers "F.Cu" "F.Mask" "F.Paste")
			(net "PVCCIN_CPU0")
		)
		(pad "2" smd rect
			(at 0 1.397)
			(size 0.762 0.889)
			(layers "F.Cu" "F.Mask" "F.Paste")
			(net "GND")
		)
		(zone
			(layer "F.Cu")
			(hatch none 0.5)
			(connect_pads
				(clearance 0)
			)
			(min_thickness 0.25)
			(keepout
				(tracks not_allowed)
				(vias allowed)
				(pads allowed)
				(copperpour not_allowed)
				(footprints allowed)
			)
			(placement
				(enabled no)
				(sheetname "")
			)
			(fill
				(thermal_gap 0.5)
				(thermal_bridge_width 0.5)
				(island_removal_mode 0)
			)
			(polygon
				(pts
					(xy 260.316472 -72.873616) (xy 261.078472 -72.873616) (xy 261.078472 -72.365616) (xy 260.316472 -72.365616)
				)
			)
		)
	)
)
